(kicad_pcb
	(version 20260206)
	(generator "pcbnew")
	(generator_version "10.0")
	(general
		(thickness 1.6)
		(legacy_teardrops no)
	)
	(paper "A4")
	(title_block
		(title "12092022_DA0F0TMDCD0_F0T_Management_Board_D_brd_V3_OCP.brd")
		(comment 1 "Grand Teton / footprints 413-418 of 1440")
	)
	(layers
		(0 "F.Cu" signal "TOP")
		(4 "In1.Cu" signal "GND")
		(6 "In2.Cu" signal "IN1")
		(8 "In3.Cu" signal "GND1")
		(10 "In4.Cu" signal "IN2")
		(12 "In5.Cu" signal "VCC")
		(14 "In6.Cu" signal "VCC1")
		(16 "In7.Cu" signal "IN3")
		(18 "In8.Cu" signal "GND2")
		(20 "In9.Cu" signal "IN4")
		(22 "In10.Cu" signal "GND3")
		(2 "B.Cu" signal "BOTTOM")
		(9 "F.Adhes" user "F.Adhesive")
		(11 "B.Adhes" user "B.Adhesive")
		(13 "F.Paste" user "Package Geometry/Pastemask Top")
		(15 "B.Paste" user "Package Geometry/Pastemask Bottom")
		(5 "F.SilkS" user "Ref Des/Silkscreen Top")
		(7 "B.SilkS" user "Ref Des/Silkscreen Bottom")
		(1 "F.Mask" user "Board Geometry/Soldermask Top")
		(3 "B.Mask" user "Board Geometry/Soldermask Bottom")
		(17 "Dwgs.User" user "User.Drawings")
		(19 "Cmts.User" user "User.Comments")
		(21 "Eco1.User" user "User.Eco1")
		(23 "Eco2.User" user "User.Eco2")
		(25 "Edge.Cuts" user "Board Geometry/Outline")
		(27 "Margin" user)
		(31 "F.CrtYd" user "Package Geometry/Place Bound Top")
		(29 "B.CrtYd" user "Package Geometry/Place Bound Bottom")
		(35 "F.Fab" user "Ref Des/Assembly Top")
		(33 "B.Fab" user "Ref Des/Assembly Bottom")
	)
	(footprint ""
		(layer "F.Cu")
		(at 36.957 -36.068 -90)
		(property "Reference" "R231"
			(at 0 0 270)
			(layer "F.SilkS")
			(hide yes)
			(effects
				(font
					(size 1.27 1.27)
				)
			)
		)
		(property "Value" ""
			(at 0 0 270)
			(layer "F.Fab")
			(effects
				(font
					(size 1.27 1.27)
				)
			)
		)
		(duplicate_pad_numbers_are_jumpers no)
		(fp_line
			(start -0.7874 0.4064)
			(end -0.7874 -0.4064)
			(stroke
				(width 0.1524)
				(type default)
			)
			(layer "F.SilkS")
		)
		(fp_line
			(start 0.7874 0.4064)
			(end -0.7874 0.4064)
			(stroke
				(width 0.1524)
				(type default)
			)
			(layer "F.SilkS")
		)
		(fp_line
			(start -0.7874 -0.4064)
			(end 0.7874 -0.4064)
			(stroke
				(width 0.1524)
				(type default)
			)
			(layer "F.SilkS")
		)
		(fp_line
			(start 0.7874 -0.4064)
			(end 0.7874 0.4064)
			(stroke
				(width 0.1524)
				(type default)
			)
			(layer "F.SilkS")
		)
		(fp_line
			(start -0.67945 0.3048)
			(end -0.67945 -0.305054)
			(stroke
				(width 0.1)
				(type default)
			)
			(layer "F.Fab")
		)
		(fp_line
			(start -0.12065 0.3048)
			(end -0.67945 0.3048)
			(stroke
				(width 0.1)
				(type default)
			)
			(layer "F.Fab")
		)
		(fp_line
			(start 0.120396 0.3048)
			(end 0.120396 0.2794)
			(stroke
				(width 0.1)
				(type default)
			)
			(layer "F.Fab")
		)
		(fp_line
			(start 0.67945 0.3048)
			(end 0.120396 0.3048)
			(stroke
				(width 0.1)
				(type default)
			)
			(layer "F.Fab")
		)
		(fp_line
			(start -0.12065 0.2794)
			(end -0.12065 0.3048)
			(stroke
				(width 0.1)
				(type default)
			)
			(layer "F.Fab")
		)
		(fp_line
			(start 0.120396 0.2794)
			(end -0.12065 0.2794)
			(stroke
				(width 0.1)
				(type default)
			)
			(layer "F.Fab")
		)
		(fp_line
			(start -0.12065 -0.2794)
			(end 0.12065 -0.2794)
			(stroke
				(width 0.1)
				(type default)
			)
			(layer "F.Fab")
		)
		(fp_line
			(start 0.12065 -0.2794)
			(end 0.12065 -0.3048)
			(stroke
				(width 0.1)
				(type default)
			)
			(layer "F.Fab")
		)
		(fp_line
			(start 0.12065 -0.3048)
			(end 0.67945 -0.3048)
			(stroke
				(width 0.1)
				(type default)
			)
			(layer "F.Fab")
		)
		(fp_line
			(start 0.67945 -0.3048)
			(end 0.67945 0.3048)
			(stroke
				(width 0.1)
				(type default)
			)
			(layer "F.Fab")
		)
		(fp_line
			(start -0.67945 -0.305054)
			(end -0.12065 -0.305054)
			(stroke
				(width 0.1)
				(type default)
			)
			(layer "F.Fab")
		)
		(fp_line
			(start -0.12065 -0.305054)
			(end -0.12065 -0.2794)
			(stroke
				(width 0.1)
				(type default)
			)
			(layer "F.Fab")
		)
		(pad "1" smd circle
			(at -0.40005 0 270)
			(size 0 0)
			(layers "F.Cu" "F.Mask" "F.Paste")
			(net "P3V3_AUX")
		)
		(pad "2" smd circle
			(at 0.40005 0 270)
			(size 0 0)
			(layers "F.Cu" "F.Mask" "F.Paste")
			(net "P3V3_P1V8_I2C_I3C")
		)
	)
	(footprint ""
		(layer "F.Cu")
		(at 85.29955 -45.697394 180)
		(property "Reference" "R331"
			(at 0 0 180)
			(layer "F.SilkS")
			(hide yes)
			(effects
				(font
					(size 1.27 1.27)
				)
			)
		)
		(property "Value" ""
			(at 0 0 180)
			(layer "F.Fab")
			(effects
				(font
					(size 1.27 1.27)
				)
			)
		)
		(duplicate_pad_numbers_are_jumpers no)
		(fp_line
			(start 0.7874 0.4064)
			(end -0.7874 0.4064)
			(stroke
				(width 0.1524)
				(type default)
			)
			(layer "F.SilkS")
		)
		(fp_line
			(start 0.7874 -0.4064)
			(end 0.7874 0.4064)
			(stroke
				(width 0.1524)
				(type default)
			)
			(layer "F.SilkS")
		)
		(fp_line
			(start -0.7874 0.4064)
			(end -0.7874 -0.4064)
			(stroke
				(width 0.1524)
				(type default)
			)
			(layer "F.SilkS")
		)
		(fp_line
			(start -0.7874 -0.4064)
			(end 0.7874 -0.4064)
			(stroke
				(width 0.1524)
				(type default)
			)
			(layer "F.SilkS")
		)
		(fp_line
			(start 0.67945 0.3048)
			(end 0.120396 0.3048)
			(stroke
				(width 0.1)
				(type default)
			)
			(layer "F.Fab")
		)
		(fp_line
			(start 0.67945 -0.3048)
			(end 0.67945 0.3048)
			(stroke
				(width 0.1)
				(type default)
			)
			(layer "F.Fab")
		)
		(fp_line
			(start 0.12065 -0.2794)
			(end 0.12065 -0.3048)
			(stroke
				(width 0.1)
				(type default)
			)
			(layer "F.Fab")
		)
		(fp_line
			(start 0.12065 -0.3048)
			(end 0.67945 -0.3048)
			(stroke
				(width 0.1)
				(type default)
			)
			(layer "F.Fab")
		)
		(fp_line
			(start 0.120396 0.3048)
			(end 0.120396 0.2794)
			(stroke
				(width 0.1)
				(type default)
			)
			(layer "F.Fab")
		)
		(fp_line
			(start 0.120396 0.2794)
			(end -0.12065 0.2794)
			(stroke
				(width 0.1)
				(type default)
			)
			(layer "F.Fab")
		)
		(fp_line
			(start -0.12065 0.3048)
			(end -0.67945 0.3048)
			(stroke
				(width 0.1)
				(type default)
			)
			(layer "F.Fab")
		)
		(fp_line
			(start -0.12065 0.2794)
			(end -0.12065 0.3048)
			(stroke
				(width 0.1)
				(type default)
			)
			(layer "F.Fab")
		)
		(fp_line
			(start -0.12065 -0.2794)
			(end 0.12065 -0.2794)
			(stroke
				(width 0.1)
				(type default)
			)
			(layer "F.Fab")
		)
		(fp_line
			(start -0.12065 -0.305054)
			(end -0.12065 -0.2794)
			(stroke
				(width 0.1)
				(type default)
			)
			(layer "F.Fab")
		)
		(fp_line
			(start -0.67945 0.3048)
			(end -0.67945 -0.305054)
			(stroke
				(width 0.1)
				(type default)
			)
			(layer "F.Fab")
		)
		(fp_line
			(start -0.67945 -0.305054)
			(end -0.12065 -0.305054)
			(stroke
				(width 0.1)
				(type default)
			)
			(layer "F.Fab")
		)
		(pad "1" smd circle
			(at -0.40005 0 180)
			(size 0 0)
			(layers "F.Cu" "F.Mask" "F.Paste")
			(net "GND")
		)
		(pad "2" smd circle
			(at 0.40005 0 180)
			(size 0 0)
			(layers "F.Cu" "F.Mask" "F.Paste")
			(net "M_BMC_DDR4_MA<5>")
		)
	)
	(footprint ""
		(layer "F.Cu")
		(at 77.947774 -70.3834)
		(property "Reference" "R876"
			(at 0 0 0)
			(layer "F.SilkS")
			(hide yes)
			(effects
				(font
					(size 1.27 1.27)
				)
			)
		)
		(property "Value" ""
			(at 0 0 0)
			(layer "F.Fab")
			(effects
				(font
					(size 1.27 1.27)
				)
			)
		)
		(duplicate_pad_numbers_are_jumpers no)
		(fp_line
			(start -0.7874 -0.4064)
			(end 0.7874 -0.4064)
			(stroke
				(width 0.1524)
				(type default)
			)
			(layer "F.SilkS")
		)
		(fp_line
			(start -0.7874 0.4064)
			(end -0.7874 -0.4064)
			(stroke
				(width 0.1524)
				(type default)
			)
			(layer "F.SilkS")
		)
		(fp_line
			(start 0.7874 -0.4064)
			(end 0.7874 0.4064)
			(stroke
				(width 0.1524)
				(type default)
			)
			(layer "F.SilkS")
		)
		(fp_line
			(start 0.7874 0.4064)
			(end -0.7874 0.4064)
			(stroke
				(width 0.1524)
				(type default)
			)
			(layer "F.SilkS")
		)
		(fp_line
			(start -0.67945 -0.305054)
			(end -0.12065 -0.305054)
			(stroke
				(width 0.1)
				(type default)
			)
			(layer "F.Fab")
		)
		(fp_line
			(start -0.67945 0.3048)
			(end -0.67945 -0.305054)
			(stroke
				(width 0.1)
				(type default)
			)
			(layer "F.Fab")
		)
		(fp_line
			(start -0.12065 -0.305054)
			(end -0.12065 -0.2794)
			(stroke
				(width 0.1)
				(type default)
			)
			(layer "F.Fab")
		)
		(fp_line
			(start -0.12065 -0.2794)
			(end 0.12065 -0.2794)
			(stroke
				(width 0.1)
				(type default)
			)
			(layer "F.Fab")
		)
		(fp_line
			(start -0.12065 0.2794)
			(end -0.12065 0.3048)
			(stroke
				(width 0.1)
				(type default)
			)
			(layer "F.Fab")
		)
		(fp_line
			(start -0.12065 0.3048)
			(end -0.67945 0.3048)
			(stroke
				(width 0.1)
				(type default)
			)
			(layer "F.Fab")
		)
		(fp_line
			(start 0.120396 0.2794)
			(end -0.12065 0.2794)
			(stroke
				(width 0.1)
				(type default)
			)
			(layer "F.Fab")
		)
		(fp_line
			(start 0.120396 0.3048)
			(end 0.120396 0.2794)
			(stroke
				(width 0.1)
				(type default)
			)
			(layer "F.Fab")
		)
		(fp_line
			(start 0.12065 -0.3048)
			(end 0.67945 -0.3048)
			(stroke
				(width 0.1)
				(type default)
			)
			(layer "F.Fab")
		)
		(fp_line
			(start 0.12065 -0.2794)
			(end 0.12065 -0.3048)
			(stroke
				(width 0.1)
				(type default)
			)
			(layer "F.Fab")
		)
		(fp_line
			(start 0.67945 -0.3048)
			(end 0.67945 0.3048)
			(stroke
				(width 0.1)
				(type default)
			)
			(layer "F.Fab")
		)
		(fp_line
			(start 0.67945 0.3048)
			(end 0.120396 0.3048)
			(stroke
				(width 0.1)
				(type default)
			)
			(layer "F.Fab")
		)
		(pad "1" smd circle
			(at -0.40005 0)
			(size 0 0)
			(layers "F.Cu" "F.Mask" "F.Paste")
			(net "PWRGD_P3V3_RGM_R3")
		)
		(pad "2" smd circle
			(at 0.40005 0)
			(size 0 0)
			(layers "F.Cu" "F.Mask" "F.Paste")
			(net "EN_P1V2_AUX_R")
		)
	)
	(footprint ""
		(layer "F.Cu")
		(at 27.1272 -65.5574 90)
		(property "Reference" "R715"
			(at 0 0 90)
			(layer "F.SilkS")
			(hide yes)
			(effects
				(font
					(size 1.27 1.27)
				)
			)
		)
		(property "Value" ""
			(at 0 0 90)
			(layer "F.Fab")
			(effects
				(font
					(size 1.27 1.27)
				)
			)
		)
		(duplicate_pad_numbers_are_jumpers no)
		(fp_line
			(start 0.7874 -0.4064)
			(end 0.7874 0.4064)
			(stroke
				(width 0.1524)
				(type default)
			)
			(layer "F.SilkS")
		)
		(fp_line
			(start -0.7874 -0.4064)
			(end 0.7874 -0.4064)
			(stroke
				(width 0.1524)
				(type default)
			)
			(layer "F.SilkS")
		)
		(fp_line
			(start 0.7874 0.4064)
			(end -0.7874 0.4064)
			(stroke
				(width 0.1524)
				(type default)
			)
			(layer "F.SilkS")
		)
		(fp_line
			(start -0.7874 0.4064)
			(end -0.7874 -0.4064)
			(stroke
				(width 0.1524)
				(type default)
			)
			(layer "F.SilkS")
		)
		(fp_line
			(start -0.12065 -0.305054)
			(end -0.12065 -0.2794)
			(stroke
				(width 0.1)
				(type default)
			)
			(layer "F.Fab")
		)
		(fp_line
			(start -0.67945 -0.305054)
			(end -0.12065 -0.305054)
			(stroke
				(width 0.1)
				(type default)
			)
			(layer "F.Fab")
		)
		(fp_line
			(start 0.67945 -0.3048)
			(end 0.67945 0.3048)
			(stroke
				(width 0.1)
				(type default)
			)
			(layer "F.Fab")
		)
		(fp_line
			(start 0.12065 -0.3048)
			(end 0.67945 -0.3048)
			(stroke
				(width 0.1)
				(type default)
			)
			(layer "F.Fab")
		)
		(fp_line
			(start 0.12065 -0.2794)
			(end 0.12065 -0.3048)
			(stroke
				(width 0.1)
				(type default)
			)
			(layer "F.Fab")
		)
		(fp_line
			(start -0.12065 -0.2794)
			(end 0.12065 -0.2794)
			(stroke
				(width 0.1)
				(type default)
			)
			(layer "F.Fab")
		)
		(fp_line
			(start 0.120396 0.2794)
			(end -0.12065 0.2794)
			(stroke
				(width 0.1)
				(type default)
			)
			(layer "F.Fab")
		)
		(fp_line
			(start -0.12065 0.2794)
			(end -0.12065 0.3048)
			(stroke
				(width 0.1)
				(type default)
			)
			(layer "F.Fab")
		)
		(fp_line
			(start 0.67945 0.3048)
			(end 0.120396 0.3048)
			(stroke
				(width 0.1)
				(type default)
			)
			(layer "F.Fab")
		)
		(fp_line
			(start 0.120396 0.3048)
			(end 0.120396 0.2794)
			(stroke
				(width 0.1)
				(type default)
			)
			(layer "F.Fab")
		)
		(fp_line
			(start -0.12065 0.3048)
			(end -0.67945 0.3048)
			(stroke
				(width 0.1)
				(type default)
			)
			(layer "F.Fab")
		)
		(fp_line
			(start -0.67945 0.3048)
			(end -0.67945 -0.305054)
			(stroke
				(width 0.1)
				(type default)
			)
			(layer "F.Fab")
		)
		(pad "1" smd circle
			(at -0.40005 0 90)
			(size 0 0)
			(layers "F.Cu" "F.Mask" "F.Paste")
			(net "UART_BMC_5_TXD_BUF1")
		)
		(pad "2" smd circle
			(at 0.40005 0 90)
			(size 0 0)
			(layers "F.Cu" "F.Mask" "F.Paste")
			(net "UART_BMC_5_TXD_BUF1_R")
		)
	)
	(footprint ""
		(layer "F.Cu")
		(at 71.501 -10.922 90)
		(property "Reference" "R470"
			(at 0 0 90)
			(layer "F.SilkS")
			(hide yes)
			(effects
				(font
					(size 1.27 1.27)
				)
			)
		)
		(property "Value" ""
			(at 0 0 90)
			(layer "F.Fab")
			(effects
				(font
					(size 1.27 1.27)
				)
			)
		)
		(duplicate_pad_numbers_are_jumpers no)
		(fp_line
			(start 0.7874 -0.4064)
			(end 0.7874 0.4064)
			(stroke
				(width 0.1524)
				(type default)
			)
			(layer "F.SilkS")
		)
		(fp_line
			(start -0.7874 -0.4064)
			(end 0.7874 -0.4064)
			(stroke
				(width 0.1524)
				(type default)
			)
			(layer "F.SilkS")
		)
		(fp_line
			(start 0.7874 0.4064)
			(end -0.7874 0.4064)
			(stroke
				(width 0.1524)
				(type default)
			)
			(layer "F.SilkS")
		)
		(fp_line
			(start -0.7874 0.4064)
			(end -0.7874 -0.4064)
			(stroke
				(width 0.1524)
				(type default)
			)
			(layer "F.SilkS")
		)
		(fp_line
			(start -0.12065 -0.305054)
			(end -0.12065 -0.2794)
			(stroke
				(width 0.1)
				(type default)
			)
			(layer "F.Fab")
		)
		(fp_line
			(start -0.67945 -0.305054)
			(end -0.12065 -0.305054)
			(stroke
				(width 0.1)
				(type default)
			)
			(layer "F.Fab")
		)
		(fp_line
			(start 0.67945 -0.3048)
			(end 0.67945 0.3048)
			(stroke
				(width 0.1)
				(type default)
			)
			(layer "F.Fab")
		)
		(fp_line
			(start 0.12065 -0.3048)
			(end 0.67945 -0.3048)
			(stroke
				(width 0.1)
				(type default)
			)
			(layer "F.Fab")
		)
		(fp_line
			(start 0.12065 -0.2794)
			(end 0.12065 -0.3048)
			(stroke
				(width 0.1)
				(type default)
			)
			(layer "F.Fab")
		)
		(fp_line
			(start -0.12065 -0.2794)
			(end 0.12065 -0.2794)
			(stroke
				(width 0.1)
				(type default)
			)
			(layer "F.Fab")
		)
		(fp_line
			(start 0.120396 0.2794)
			(end -0.12065 0.2794)
			(stroke
				(width 0.1)
				(type default)
			)
			(layer "F.Fab")
		)
		(fp_line
			(start -0.12065 0.2794)
			(end -0.12065 0.3048)
			(stroke
				(width 0.1)
				(type default)
			)
			(layer "F.Fab")
		)
		(fp_line
			(start 0.67945 0.3048)
			(end 0.120396 0.3048)
			(stroke
				(width 0.1)
				(type default)
			)
			(layer "F.Fab")
		)
		(fp_line
			(start 0.120396 0.3048)
			(end 0.120396 0.2794)
			(stroke
				(width 0.1)
				(type default)
			)
			(layer "F.Fab")
		)
		(fp_line
			(start -0.12065 0.3048)
			(end -0.67945 0.3048)
			(stroke
				(width 0.1)
				(type default)
			)
			(layer "F.Fab")
		)
		(fp_line
			(start -0.67945 0.3048)
			(end -0.67945 -0.305054)
			(stroke
				(width 0.1)
				(type default)
			)
			(layer "F.Fab")
		)
		(pad "1" smd circle
			(at -0.40005 0 90)
			(size 0 0)
			(layers "F.Cu" "F.Mask" "F.Paste")
			(net "REAR_AC_PWR_BTN")
		)
		(pad "2" smd circle
			(at 0.40005 0 90)
			(size 0 0)
			(layers "F.Cu" "F.Mask" "F.Paste")
			(net "REAR_AC_PWR_BTN_N")
		)
	)
	(footprint ""
		(layer "F.Cu")
		(at 85.172296 -74.18959 180)
		(property "Reference" "PR498"
			(at 0 0 180)
			(layer "F.SilkS")
			(hide yes)
			(effects
				(font
					(size 1.27 1.27)
				)
			)
		)
		(property "Value" ""
			(at 0 0 180)
			(layer "F.Fab")
			(effects
				(font
					(size 1.27 1.27)
				)
			)
		)
		(duplicate_pad_numbers_are_jumpers no)
		(fp_line
			(start 0.7874 0.4064)
			(end -0.7874 0.4064)
			(stroke
				(width 0.1524)
				(type default)
			)
			(layer "F.SilkS")
		)
		(fp_line
			(start 0.7874 -0.4064)
			(end 0.7874 0.4064)
			(stroke
				(width 0.1524)
				(type default)
			)
			(layer "F.SilkS")
		)
		(fp_line
			(start -0.7874 0.4064)
			(end -0.7874 -0.4064)
			(stroke
				(width 0.1524)
				(type default)
			)
			(layer "F.SilkS")
		)
		(fp_line
			(start -0.7874 -0.4064)
			(end 0.7874 -0.4064)
			(stroke
				(width 0.1524)
				(type default)
			)
			(layer "F.SilkS")
		)
		(fp_line
			(start 0.67945 0.3048)
			(end 0.120396 0.3048)
			(stroke
				(width 0.1)
				(type default)
			)
			(layer "F.Fab")
		)
		(fp_line
			(start 0.67945 -0.3048)
			(end 0.67945 0.3048)
			(stroke
				(width 0.1)
				(type default)
			)
			(layer "F.Fab")
		)
		(fp_line
			(start 0.12065 -0.2794)
			(end 0.12065 -0.3048)
			(stroke
				(width 0.1)
				(type default)
			)
			(layer "F.Fab")
		)
		(fp_line
			(start 0.12065 -0.3048)
			(end 0.67945 -0.3048)
			(stroke
				(width 0.1)
				(type default)
			)
			(layer "F.Fab")
		)
		(fp_line
			(start 0.120396 0.3048)
			(end 0.120396 0.2794)
			(stroke
				(width 0.1)
				(type default)
			)
			(layer "F.Fab")
		)
		(fp_line
			(start 0.120396 0.2794)
			(end -0.12065 0.2794)
			(stroke
				(width 0.1)
				(type default)
			)
			(layer "F.Fab")
		)
		(fp_line
			(start -0.12065 0.3048)
			(end -0.67945 0.3048)
			(stroke
				(width 0.1)
				(type default)
			)
			(layer "F.Fab")
		)
		(fp_line
			(start -0.12065 0.2794)
			(end -0.12065 0.3048)
			(stroke
				(width 0.1)
				(type default)
			)
			(layer "F.Fab")
		)
		(fp_line
			(start -0.12065 -0.2794)
			(end 0.12065 -0.2794)
			(stroke
				(width 0.1)
				(type default)
			)
			(layer "F.Fab")
		)
		(fp_line
			(start -0.12065 -0.305054)
			(end -0.12065 -0.2794)
			(stroke
				(width 0.1)
				(type default)
			)
			(layer "F.Fab")
		)
		(fp_line
			(start -0.67945 0.3048)
			(end -0.67945 -0.305054)
			(stroke
				(width 0.1)
				(type default)
			)
			(layer "F.Fab")
		)
		(fp_line
			(start -0.67945 -0.305054)
			(end -0.12065 -0.305054)
			(stroke
				(width 0.1)
				(type default)
			)
			(layer "F.Fab")
		)
		(pad "1" smd circle
			(at -0.40005 0 180)
			(size 0 0)
			(layers "F.Cu" "F.Mask" "F.Paste")
			(net "P3V3_AUX")
		)
		(pad "2" smd circle
			(at 0.40005 0 180)
			(size 0 0)
			(layers "F.Cu" "F.Mask" "F.Paste")
			(net "PWRGD_P1V2_AUX_R")
		)
	)
)
